# BASEBOARD_FAB2 (Tioga Pass) — schematic netlist excerpt (pin names and nets, part order shuffled) for the footprints in the layout excerpt that follows; sources: Cadence DE-HDL packaged netlist, KiCad conversion of Wiwynn_Tioga_Pass_MB.brd

C8D1  CAP_A  0.1UF 16V 10% X7R  pkg 0402V  page 157 : A = P3V3_STBY ; B = GND
R4T3  RES  10.0 1% CHIP  pkg 0402  page 99 : A = SMB_DDR_ABC_SCL_G_R ; B = SMB_DDR_ABC_SCL_G
C8P10  CAP  47UF 4V 20% X6S  pkg 0805  page 76 : A = PVCCIN_CPU1 ; B = GND

(kicad_pcb
	(version 20260206)
	(generator "pcbnew")
	(generator_version "10.0")
	(general
		(thickness 1.6)
		(legacy_teardrops no)
	)
	(paper "A4")
	(title_block
		(title "Wiwynn_Tioga_Pass_MB.brd")
		(comment 1 "Tioga Pass / footprints 4182-4184 of 4770")
	)
	(layers
		(0 "F.Cu" signal "TOP")
		(4 "In1.Cu" signal "L2GND")
		(6 "In2.Cu" signal "L3")
		(8 "In3.Cu" signal "L4GND")
		(10 "In4.Cu" signal "L5")
		(12 "In5.Cu" signal "L6GND")
		(14 "In6.Cu" signal "L7VCC")
		(16 "In7.Cu" signal "L8VCC")
		(18 "In8.Cu" signal "L9GND")
		(20 "In9.Cu" signal "L10")
		(22 "In10.Cu" signal "L11GND")
		(24 "In11.Cu" signal "L12")
		(26 "In12.Cu" signal "L13GND")
		(2 "B.Cu" signal "BOTTOM")
		(9 "F.Adhes" user "F.Adhesive")
		(11 "B.Adhes" user "B.Adhesive")
		(13 "F.Paste" user "Package Geometry/Pastemask Top")
		(15 "B.Paste" user "Package Geometry/Pastemask Bottom")
		(5 "F.SilkS" user "Ref Des/Silkscreen Top")
		(7 "B.SilkS" user "Ref Des/Silkscreen Bottom")
		(1 "F.Mask" user "Board Geometry/Soldermask Top")
		(3 "B.Mask" user "Board Geometry/Soldermask Bottom")
		(17 "Dwgs.User" user "User.Drawings")
		(19 "Cmts.User" user "User.Comments")
		(21 "Eco1.User" user "User.Eco1")
		(23 "Eco2.User" user "User.Eco2")
		(25 "Edge.Cuts" user "Board Geometry/Outline")
		(27 "Margin" user)
		(31 "F.CrtYd" user "Package Geometry/Place Bound Top")
		(29 "B.CrtYd" user "Package Geometry/Place Bound Bottom")
		(35 "F.Fab" user "Ref Des/Assembly Top")
		(33 "B.Fab" user "Ref Des/Assembly Bottom")
	)
	(footprint ""
		(layer "B.Cu")
		(at 452.278242 -29.786326)
		(property "Reference" "C8D1"
			(at 0 0 0)
			(layer "B.SilkS")
			(hide yes)
			(effects
				(font
					(size 1.27 1.27)
				)
				(justify mirror)
			)
		)
		(property "Value" ""
			(at 0 0 0)
			(layer "B.Fab")
			(effects
				(font
					(size 1.27 1.27)
				)
				(justify mirror)
			)
		)
		(duplicate_pad_numbers_are_jumpers no)
		(fp_poly
			(pts
				(xy -0.3048 -0.1016) (xy -0.3048 0.9906) (xy 0.3048 0.9906) (xy 0.3048 -0.1016)
			)
			(stroke
				(width 0)
				(type default)
			)
			(fill no)
			(layer "B.CrtYd")
		)
		(fp_line
			(start -0.3048 -0.1016)
			(end 0.3048 -0.1016)
			(stroke
				(width 0.1)
				(type default)
			)
			(layer "B.Fab")
		)
		(fp_line
			(start -0.3048 0.9906)
			(end -0.3048 -0.1016)
			(stroke
				(width 0.1)
				(type default)
			)
			(layer "B.Fab")
		)
		(fp_line
			(start 0.3048 -0.1016)
			(end 0.3048 0.9906)
			(stroke
				(width 0.1)
				(type default)
			)
			(layer "B.Fab")
		)
		(fp_line
			(start 0.3048 0.9906)
			(end -0.3048 0.9906)
			(stroke
				(width 0.1)
				(type default)
			)
			(layer "B.Fab")
		)
		(pad "1" smd rect
			(at 0 0 180)
			(size 0.508 0.508)
			(layers "B.Cu" "B.Mask" "B.Paste")
			(net "P3V3_STBY")
		)
		(pad "2" smd rect
			(at 0 0.889 180)
			(size 0.508 0.508)
			(layers "B.Cu" "B.Mask" "B.Paste")
			(net "GND")
		)
		(zone
			(layer "B.Cu")
			(hatch none 0.5)
			(connect_pads
				(clearance 0)
			)
			(min_thickness 0.25)
			(keepout
				(tracks allowed)
				(vias not_allowed)
				(pads allowed)
				(copperpour not_allowed)
				(footprints allowed)
			)
			(placement
				(enabled no)
				(sheetname "")
			)
			(fill
				(thermal_gap 0.5)
				(thermal_bridge_width 0.5)
				(island_removal_mode 0)
			)
			(polygon
				(pts
					(xy 452.532242 -29.532326) (xy 452.024242 -29.532326) (xy 452.024242 -29.151326) (xy 452.532242 -29.151326)
				)
			)
		)
		(zone
			(layer "B.Cu")
			(hatch none 0.5)
			(connect_pads
				(clearance 0)
			)
			(min_thickness 0.25)
			(keepout
				(tracks not_allowed)
				(vias allowed)
				(pads allowed)
				(copperpour not_allowed)
				(footprints allowed)
			)
			(placement
				(enabled no)
				(sheetname "")
			)
			(fill
				(thermal_gap 0.5)
				(thermal_bridge_width 0.5)
				(island_removal_mode 0)
			)
			(polygon
				(pts
					(xy 452.532242 -29.151326) (xy 452.024242 -29.151326) (xy 452.024242 -29.532326) (xy 452.532242 -29.532326)
				)
			)
		)
	)
	(footprint ""
		(layer "B.Cu")
		(at 103.073454 -79.60614 180)
		(property "Reference" "C8P10"
			(at 0 0 0)
			(layer "B.SilkS")
			(hide yes)
			(effects
				(font
					(size 1.27 1.27)
				)
				(justify mirror)
			)
		)
		(property "Value" ""
			(at 0 0 0)
			(layer "B.Fab")
			(effects
				(font
					(size 1.27 1.27)
				)
				(justify mirror)
			)
		)
		(duplicate_pad_numbers_are_jumpers no)
		(fp_poly
			(pts
				(xy 0.7239 -0.2159) (xy -0.7239 -0.2159) (xy -0.7239 1.9939) (xy 0.7239 1.9939)
			)
			(stroke
				(width 0)
				(type default)
			)
			(fill no)
			(layer "B.CrtYd")
		)
		(fp_line
			(start 0.7239 1.9939)
			(end -0.7239 1.9939)
			(stroke
				(width 0.1)
				(type default)
			)
			(layer "B.Fab")
		)
		(fp_line
			(start 0.7239 -0.2159)
			(end 0.7239 1.9939)
			(stroke
				(width 0.1)
				(type default)
			)
			(layer "B.Fab")
		)
		(fp_line
			(start -0.7239 1.9939)
			(end -0.7239 -0.2159)
			(stroke
				(width 0.1)
				(type default)
			)
			(layer "B.Fab")
		)
		(fp_line
			(start -0.7239 -0.2159)
			(end 0.7239 -0.2159)
			(stroke
				(width 0.1)
				(type default)
			)
			(layer "B.Fab")
		)
		(pad "1" smd rect
			(at 0 0)
			(size 1.27 1.016)
			(layers "B.Cu" "B.Mask" "B.Paste")
			(net "PVCCIN_CPU1")
		)
		(pad "2" smd rect
			(at 0 1.778)
			(size 1.27 1.016)
			(layers "B.Cu" "B.Mask" "B.Paste")
			(net "GND")
		)
		(zone
			(layer "B.Cu")
			(hatch none 0.5)
			(connect_pads
				(clearance 0)
			)
			(min_thickness 0.25)
			(keepout
				(tracks not_allowed)
				(vias allowed)
				(pads allowed)
				(copperpour not_allowed)
				(footprints allowed)
			)
			(placement
				(enabled no)
				(sheetname "")
			)
			(fill
				(thermal_gap 0.5)
				(thermal_bridge_width 0.5)
				(island_removal_mode 0)
			)
			(polygon
				(pts
					(xy 102.438454 -80.11414) (xy 103.708454 -80.11414) (xy 103.708454 -80.87614) (xy 102.438454 -80.87614)
				)
			)
		)
	)
	(footprint ""
		(layer "B.Cu")
		(at 323.8627 -32.93618 -90)
		(property "Reference" "R4T3"
			(at 0 0 90)
			(layer "B.SilkS")
			(hide yes)
			(effects
				(font
					(size 1.27 1.27)
				)
				(justify mirror)
			)
		)
		(property "Value" ""
			(at 0 0 90)
			(layer "B.Fab")
			(effects
				(font
					(size 1.27 1.27)
				)
				(justify mirror)
			)
		)
		(duplicate_pad_numbers_are_jumpers no)
		(fp_poly
			(pts
				(xy 0.2794 -0.1016) (xy -0.2794 -0.1016) (xy -0.2794 0.9906) (xy 0.2794 0.9906)
			)
			(stroke
				(width 0)
				(type default)
			)
			(fill no)
			(layer "B.CrtYd")
		)
		(fp_line
			(start -0.2794 0.9906)
			(end -0.2794 -0.1016)
			(stroke
				(width 0.1)
				(type default)
			)
			(layer "B.Fab")
		)
		(fp_line
			(start 0.2794 0.9906)
			(end -0.2794 0.9906)
			(stroke
				(width 0.1)
				(type default)
			)
			(layer "B.Fab")
		)
		(fp_line
			(start -0.2794 -0.1016)
			(end 0.2794 -0.1016)
			(stroke
				(width 0.1)
				(type default)
			)
			(layer "B.Fab")
		)
		(fp_line
			(start 0.2794 -0.1016)
			(end 0.2794 0.9906)
			(stroke
				(width 0.1)
				(type default)
			)
			(layer "B.Fab")
		)
		(pad "1" smd rect
			(at 0 0 90)
			(size 0.508 0.508)
			(layers "B.Cu" "B.Mask" "B.Paste")
			(net "SMB_DDR_ABC_SCL_G_R")
		)
		(pad "2" smd rect
			(at 0 0.889 90)
			(size 0.508 0.508)
			(layers "B.Cu" "B.Mask" "B.Paste")
			(net "SMB_DDR_ABC_SCL_G")
		)
		(zone
			(layer "B.Cu")
			(hatch none 0.5)
			(connect_pads
				(clearance 0)
			)
			(min_thickness 0.25)
			(keepout
				(tracks not_allowed)
				(vias allowed)
				(pads allowed)
				(copperpour not_allowed)
				(footprints allowed)
			)
			(placement
				(enabled no)
				(sheetname "")
			)
			(fill
				(thermal_gap 0.5)
				(thermal_bridge_width 0.5)
				(island_removal_mode 0)
			)
			(polygon
				(pts
					(xy 323.2277 -32.68218) (xy 323.2277 -33.19018) (xy 323.6087 -33.19018) (xy 323.6087 -32.68218)
				)
			)
		)
		(zone
			(layer "B.Cu")
			(hatch none 0.5)
			(connect_pads
				(clearance 0)
			)
			(min_thickness 0.25)
			(keepout
				(tracks allowed)
				(vias not_allowed)
				(pads allowed)
				(copperpour not_allowed)
				(footprints allowed)
			)
			(placement
				(enabled no)
				(sheetname "")
			)
			(fill
				(thermal_gap 0.5)
				(thermal_bridge_width 0.5)
				(island_removal_mode 0)
			)
			(polygon
				(pts
					(xy 323.6087 -32.68218) (xy 323.6087 -33.19018) (xy 323.2277 -33.19018) (xy 323.2277 -32.68218)
				)
			)
		)
	)
)
